FILE_TYPE = CONNECTIVITY;
{Allegro Design Entry HDL 17.2-2016 S081 (4005846) 1/11/2022}
"PAGE_NUMBER" = 311;
0"NC";
1"P3V3_AUX\g";
2"P3V3_AUX\g";
3"HP_LVC3_SCM_HSC_PWRGD_PLD";
4"HP_LVC3_OCP_V3_1_PWRGD_R"$PHYS_NET_NAME"RST_PCIE_M2_N"CDS_PHYS_NET_NAME"HP_LVC3_OCP_V3_1_PWRGD_R";
5"HP_LVC3_OCP_V3_2_PWRGD_R"$PHYS_NET_NAME"RST_PCIE_M2_N"CDS_PHYS_NET_NAME"HP_LVC3_OCP_V3_1_PWRGD_R";
6"HP_LVC3_E1S_0_HSC_PWRGD"$PHYS_NET_NAME"RST_PCIE_M2_N"CDS_PHYS_NET_NAME"HP_LVC3_OCP_V3_1_PWRGD_R";
7"HP_LVC3_SCM_HSC_PWRGD";
8"HP_LVC3_SCM_HSC_PWRGD_PLD";
9"HP_E1S_0_P3V3_PWRGD_PLD";
10"HP_LVC3_E1S_0_HSC_PWRGD_PLD"$PHYS_NET_NAME"RST_PCIE_M2_N"CDS_PHYS_NET_NAME"HP_LVC3_OCP_V3_1_PWRGD_R";
11"HP_LVC3_E1S_0_HSC_PWRGD_PLD"$PHYS_NET_NAME"RST_PCIE_M2_N"CDS_PHYS_NET_NAME"HP_LVC3_OCP_V3_1_PWRGD_R";
12"E1S_0_CLK_OE_N";
13"PU_FPGA_D12_PROGRAMN";
14"JTAG_PLD_JTAGEN"CDS_PHYS_NET_NAME"JTAG_PLD_JTAGEN";
15"JTAG_PLD_TMS_R"CDS_PHYS_NET_NAME"JTAG_PLD_TMS_R";
16"JTAG_PLD_TCK_R"CDS_PHYS_NET_NAME"JTAG_PLD_TCK_R";
17"NC_FPGA_PT44C"CDS_PHYS_NET_NAME"PWRGD_PCH_PWROK_R";
18"NC_FPGA_PT44D"CDS_PHYS_NET_NAME"PWRGD_PCH_PWROK_R";
19"HP_LVC3_OCP_V3_2_FUSE_PWRGD"$PHYS_NET_NAME"RST_PCIE_M2_N"CDS_PHYS_NET_NAME"HP_LVC3_OCP_V3_1_PWRGD_R";
20"HP_LVC3_OCP_V3_1_FUSE_PWRGD"$PHYS_NET_NAME"RST_PCIE_M2_N"CDS_PHYS_NET_NAME"HP_LVC3_OCP_V3_1_PWRGD_R";
21"HP_LVC3_OCP_V3_2_PRSNT2_PLD_N"CDS_PHYS_NET_NAME"HP_LVC3_OCP_V3_2_PRSNT2_PLD_N";
22"HP_LVC3_OCP_V3_1_PRSNT2_PLD_N"CDS_PHYS_NET_NAME"HP_LVC3_OCP_V3_1_PRSNT2_N";
23"HP_LVC3_OCP_V3_2_FUSE_PWRGD"$PHYS_NET_NAME"RST_PCIE_M2_N"CDS_PHYS_NET_NAME"HP_LVC3_OCP_V3_2_PWRGD_R";
24"HP_LVC3_OCP_V3_1_FUSE_PWRGD"$PHYS_NET_NAME"RST_PCIE_M2_N"CDS_PHYS_NET_NAME"HP_LVC3_OCP_V3_1_PWRGD_R";
25"RST_CPU0_DRAM_CD_PLD_LVT3_N"CDS_PHYS_NET_NAME"RST_CPU0_DRAM_CD_PLD_N";
26"RST_CPU1_DRAM_CD_PLD_LVT3_N"CDS_PHYS_NET_NAME"RST_CPU1_DRAM_CD_PLD_N";
27"RST_CPU0_DRAM_GH_PLD_LVT3_N"CDS_PHYS_NET_NAME"RST_CPU0_DRAM_GH_PLD_N";
28"RST_PLD_CPU1_DRAM_CD_N"CDS_PHYS_NET_NAME"RST_PLD_CPU1_DRAM_CD_N";
29"RST_MB_STBY_R_N"CDS_PHYS_NET_NAME"RST_MB_STBY_R_N";
30"RST_CPU1_DRAM_AB_PLD_LVT3_N"CDS_PHYS_NET_NAME"RST_CPU1_DRAM_AB_PLD_N";
31"RST_CPU1_DRAM_GH_PLD_LVT3_N"CDS_PHYS_NET_NAME"RST_CPU1_DRAM_GH_PLD_N";
32"RST_PLD_CPU0_DRAM_CD_N"CDS_PHYS_NET_NAME"RST_PLD_CPU0_DRAM_CD_N";
33"RST_CPU0_DRAM_EF_PLD_LVT3_N"CDS_PHYS_NET_NAME"RST_CPU0_DRAM_EF_PLD_N";
34"RST_CPU0_DRAM_AB_PLD_LVT3_N"CDS_PHYS_NET_NAME"RST_CPU0_DRAM_AB_PLD_N";
35"RST_CPU1_DRAM_EF_PLD_LVT3_N"CDS_PHYS_NET_NAME"RST_CPU1_DRAM_EF_PLD_N";
36"RST_PLD_CPU0_DRAM_AB_N"CDS_PHYS_NET_NAME"RST_PLD_CPU0_DRAM_AB_N";
37"RST_PLD_CPU0_DRAM_EF_N"CDS_PHYS_NET_NAME"RST_PLD_CPU0_DRAM_EF_N";
38"RST_PLD_CPU0_DRAM_GH_N"CDS_PHYS_NET_NAME"RST_PLD_CPU0_DRAM_GH_N";
39"RST_PLD_CPU1_DRAM_AB_N"CDS_PHYS_NET_NAME"RST_PLD_CPU1_DRAM_AB_N";
40"H_CPU0_MEMHOT_OUT_LVC1_N"CDS_PHYS_NET_NAME"H_CPU0_MEMHOT_OUT_LVC1_N";
41"H_CPU0_THERMTRIP_LVC1_N"CDS_PHYS_NET_NAME"H_CPU0_THERMTRIP_LVC1_N";
42"PWRGD_DRAMPWRGD_CPU0_AB_R_LVC1"CDS_PHYS_NET_NAME"PWRGD_DRAMPWRGD_CPU0_AB_R_LVC1";
43"PWRGD_DRAMPWRGD_CPU0_CD_R_LVC1"CDS_PHYS_NET_NAME"PWRGD_DRAMPWRGD_CPU0_CD_R_LVC1";
44"H_CPU1_MEMHOT_IN_LVC1_R_N"CDS_PHYS_NET_NAME"H_CPU1_MEMHOT_IN_LVC1_R_N";
45"H_CPU1_THERMTRIP_LVC1_N"CDS_PHYS_NET_NAME"H_CPU1_THERMTRIP_LVC1_N";
46"H_CPU1_PROCHOT_LVC1_R_N"CDS_PHYS_NET_NAME"H_CPU1_PROCHOT_LVC1_R_N";
47"PWRGD_DRAMPWRGD_CPU1_EF_R_LVC1"CDS_PHYS_NET_NAME"PWRGD_DRAMPWRGD_CPU1_EF_R_LVC1";
48"PWRGD_DRAMPWRGD_CPU1_AB_R_LVC1"CDS_PHYS_NET_NAME"PWRGD_DRAMPWRGD_CPU1_AB_R_LVC1";
49"PWRGD_DRAMPWRGD_CPU0_GH_R_LVC1"CDS_PHYS_NET_NAME"PWRGD_DRAMPWRGD_CPU0_GH_R_LVC1";
50"PWRGD_DRAMPWRGD_CPU0_EF_R_LVC1"CDS_PHYS_NET_NAME"PWRGD_DRAMPWRGD_CPU0_EF_R_LVC1";
51"PWRGD_DRAMPWRGD_CPU1_GH_R_LVC1"CDS_PHYS_NET_NAME"PWRGD_DRAMPWRGD_CPU1_GH_R_LVC1";
52"FM_BOARD_BMC_SKU_ID4"CDS_PHYS_NET_NAME"PWRGD_DRAMPWRGD_CPU0_AB_R_LVC1";
53"FM_BOARD_BMC_SKU_ID3"CDS_PHYS_NET_NAME"PWRGD_DRAMPWRGD_CPU0_CD_R_LVC1";
54"FM_BOARD_BMC_SKU_ID2"CDS_PHYS_NET_NAME"PWRGD_DRAMPWRGD_CPU0_EF_R_LVC1";
55"FAB_BMC_REV_ID2"CDS_PHYS_NET_NAME"PWRGD_DRAMPWRGD_CPU1_CD_R_LVC1";
56"FM_BOARD_BMC_SKU_ID0"CDS_PHYS_NET_NAME"PWRGD_DRAMPWRGD_CPU1_AB_R_LVC1";
57"FM_BOARD_BMC_SKU_ID1"CDS_PHYS_NET_NAME"PWRGD_DRAMPWRGD_CPU0_GH_R_LVC1";
58"PWRGD_DRAMPWRGD_CPU1_CD_R_LVC1"CDS_PHYS_NET_NAME"PWRGD_DRAMPWRGD_CPU1_CD_R_LVC1";
59"FAB_BMC_REV_ID1"CDS_PHYS_NET_NAME"PWRGD_DRAMPWRGD_CPU1_EF_R_LVC1";
60"FAB_BMC_REV_ID0"CDS_PHYS_NET_NAME"PWRGD_DRAMPWRGD_CPU1_GH_R_LVC1";
61"H_CPU0_MEMHOT_IN_LVC1_R_N"CDS_PHYS_NET_NAME"H_CPU0_MEMHOT_IN_LVC1_R_N";
62"H_CPU0_PROCHOT_LVC1_R_N"CDS_PHYS_NET_NAME"H_CPU0_PROCHOT_LVC1_R_N";
63"H_CPU_CATERR_LVC2_R2_N"CDS_PHYS_NET_NAME"H_CPU_CATERR_LVC1_R_N";
64"FM_THERMTRIP_DLY_LVC1_R_N"CDS_PHYS_NET_NAME"FM_THERMTRIP_DLY_LVC1_R_N";
65"H_CPU_NMI_LVC1_R_N"CDS_PHYS_NET_NAME"H_CPU_NMI_LVC1_R_N";
66"H_CPU_RMCA_LVC2_R2_N"CDS_PHYS_NET_NAME"H_CPU_RMCA_LVC1_R_N";
67"RST_CPU0_LVC1_R_N"CDS_PHYS_NET_NAME"RST_CPU0_LVC1_R_N";
68"RST_CPU1_LVC1_R_N"CDS_PHYS_NET_NAME"RST_CPU1_LVC1_R_N";
69"PWRGD_CPU0_LVC1_R"CDS_PHYS_NET_NAME"PWRGD_CPU0_LVC1_R";
70"PWRGD_CPU1_LVC1_R"CDS_PHYS_NET_NAME"PWRGD_CPU1_LVC1_R";
71"H_CPU1_MEMHOT_OUT_LVC1_N"CDS_PHYS_NET_NAME"H_CPU1_MEMHOT_OUT_LVC1_N";
72"H_CPU1_MEMTRIP_LVC1_N"CDS_PHYS_NET_NAME"H_CPU1_MEMTRIP_LVC1_N";
73"H_CPU_ERR1_LVC2_N"CDS_PHYS_NET_NAME"H_CPU_ERR1_LVC1_N";
74"H_CPU_ERR0_LVC2_N"CDS_PHYS_NET_NAME"H_CPU_ERR0_LVC1_N";
75"RST_PLD_CPU1_DRAM_EF_N"CDS_PHYS_NET_NAME"RST_PLD_CPU1_DRAM_EF_N";
76"JTAG_PLD_TDI_R"CDS_PHYS_NET_NAME"JTAG_PLD_TDI_R";
77"JTAG_PLD_TDO_R"CDS_PHYS_NET_NAME"JTAG_PLD_TDO_R";
78"PWRGD_CPUPWRGD_LVC2_R1"CDS_PHYS_NET_NAME"PWRGD_CPUPWRGD_LVC1";
79"H_CPU0_MEMTRIP_LVC1_N"CDS_PHYS_NET_NAME"H_CPU0_MEMTRIP_LVC1_N";
80"H_CPU_ERR2_LVC2_N"CDS_PHYS_NET_NAME"H_CPU_ERR2_LVC1_N";
81"RST_PLD_CPU1_DRAM_GH_N"CDS_PHYS_NET_NAME"RST_PLD_CPU1_DRAM_GH_N";
%"UNIVERSAL_POWER"
"1","(1300,350)","0","logical_power","I28";
;
HDL_POWER"P3V3_AUX"
CDS_LIB"logical_power";
"A"2;
%"Q_RES"
"2","(1300,50)","0","pure_quanta","I29";
;
PART_NUMBER"CS31002FB08"
PACK_TYPE"0402LF"
VALUE"10K"
WATTAGE"1/16W"
TOLERANCE"1%"
MATERIAL"CHIP"
$LOCATION"R3249"
CDS_LIB"pure_quanta"
CDS_LOCATION"R3249"
$SEC"1"
CDS_SEC"1";
"A"
$PN"1"2;
"B"
$PN"2"13;
%"UNIVERSAL_POWER"
"1","(4175,3575)","0","logical_power","I3";
;
HDL_POWER"P3V3_AUX"
CDS_LIB"logical_power";
"A"1;
%"LCMXO3LF9400C5BG484C"
"1","(-875,2075)","0","pure_quanta","I33";
;
PART_NUMBER"AJ094000T08"
VALUE"LCMXO3LF-9400C-5BG484C"
PART_TYPE"SMLF"
MATERIAL"IC"
$LOCATION"U249"
CDS_LMAN_SYM_OUTLINE"-500,1400,500,-1400"
NEEDS_NO_SIZE"TRUE"
CDS_LIB"pure_quanta"
CDS_LOCATION"U249"
$SEC"1"
CDS_SEC"1";
"PL12D"
$PN"K6"60;
"PL12C"
$PN"K7"59;
"PL12B"
$PN"J1"55;
"PL12A"
$PN"J2"56;
"PL11D"
$PN"J3"57;
"PL11C"
$PN"J4"54;
"PL11B"
$PN"J5"53;
"PL11A"
$PN"H5"52;
"PL10D"
$PN"J6"51;
"PL10C"
$PN"J7"47;
"PL10B"
$PN"H1"58;
"PL10A"
$PN"H2"48;
"PL7D"
$PN"H3"49;
"PL7C"
$PN"H4"50;
"PL7B||PCLKC5_0"
$PN"G1"43;
"PL7A||PCLKT5_0"
$PN"G2"42;
"PL30D"
$PN"T7"61;
"PL30C"
$PN"V5"44;
"PL30B"
$PN"W4"62;
"PL30A"
$PN"Y3"46;
"PL29D"
$PN"Y2"63;
"PL29C"
$PN"W3"64;
"PL29B"
$PN"AA1"65;
"PL29A"
$PN"Y1"66;
"PL28D"
$PN"U5"67;
"PL28C"
$PN"V4"68;
"PL28B"
$PN"W2"69;
"PL28A"
$PN"W1"70;
"PL27D"
$PN"U4"0;
"PL27C"
$PN"U3"0;
"PL27B||PCLKC3_0"
$PN"V1"0;
"PL27A||PCLKT3_0"
$PN"U2"0;
"PL19D"
$PN"M7"0;
"PL19C"
$PN"P3"0;
"PL19B"
$PN"R1"0;
"PL19A"
$PN"P2"0;
"PL18D"
$PN"N4"0;
"PL18C"
$PN"N3"0;
"PL18B"
$PN"P1"0;
"PL18A"
$PN"N2"0;
"PL17D"
$PN"M5"0;
"PL17C"
$PN"M6"0;
"PL17B"
$PN"N1"0;
"PL17A"
$PN"M1"0;
"PL26B"
$PN"T4"80;
"PL26A"
$PN"T3"40;
"PL25D"
$PN"R7"71;
"PL25C"
$PN"R6"79;
"PL24D"
$PN"P7"45;
"PL24C"
$PN"R5"0;
"PL24B"
$PN"R4"0;
"PL24A"
$PN"R3"0;
"PL25B"
$PN"U1"72;
"PL25A"
$PN"T2"41;
"PL6B"
$PN"F1"0;
"PL6A"
$PN"E1"0;
"PL6D"
$PN"G4"0;
"PL6C"
$PN"G3"0;
"PL16D"
$PN"L4"0;
"PL16C"
$PN"L3"0;
"PL14D"
$PN"L5"8;
"PL14C"
$PN"L6"12;
"PL26D"
$PN"T6"74;
"PL26C"
$PN"T5"73;
"PL21D"
$PN"P6"0;
"PL21C"
$PN"P5"78;
"PL21B"
$PN"T1"0;
"PL21A"
$PN"R2"0;
"PL20D"
$PN"N7"0;
"PL20C"
$PN"N6"0;
"PL20B"
$PN"N5"0;
"PL20A"
$PN"P4"0;
"PL16B||PCLKC4_0"
$PN"M2"0;
"PL16A||PCLKT4_0"
$PN"L1"0;
"PL14B"
$PN"K1"9;
"PL14A"
$PN"K2"10;
"PL13D"
$PN"K3"21;
"PL13C"
$PN"K4"22;
"PL13B"
$PN"K5"23;
"PL13A"
$PN"L7"24;
"PL5D"
$PN"F4"81;
"PL5C"
$PN"E3"75;
"PL5B"
$PN"E2"28;
"PL5A"
$PN"D1"39;
"PL4D"
$PN"H6"38;
"PL4C"
$PN"G5"37;
"PL4B||L_GPLLC_IN"
$PN"D2"32;
"PL4A||L_GPLLT_IN"
$PN"C1"36;
"PL3D"
$PN"H7"31;
"PL3C"
$PN"G6"35;
"PL3B||L_GPLLC_FB"
$PN"F5"26;
"PL3A||L_GPLLT_FB"
$PN"E4"30;
"PL2D"
$PN"G7"27;
"PL2C"
$PN"F6"33;
"PL2B"
$PN"D4"25;
"PL2A"
$PN"D3"34;
%"Q_RES"
"2","(4175,3350)","0","pure_quanta","I4";
;
PART_NUMBER"CS21002FB06"
VALUE"1K"
TOLERANCE"1%"
PACK_TYPE"0402LF"
MATERIAL"CHIP"
WATTAGE"1/16W"
$LOCATION"R1823"
CDS_LIB"pure_quanta"
CDS_LOCATION"R1823"
$SEC"1"
CDS_SEC"1";
"A"
$PN"1"1;
"B"
$PN"2"29;
%"LCMXO3LF9400C5BG484C"
"4","(-925,-175)","0","pure_quanta","I70";
;
PART_NUMBER"AJ094000T08"
MATERIAL"IC"
PART_TYPE"SMLF"
VALUE"LCMXO3LF-9400C-5BG484C"
$LOCATION"U249"
CDS_LMAN_SYM_OUTLINE"-400,250,400,-250"
NEEDS_NO_SIZE"TRUE"
CDS_LIB"pure_quanta"
CDS_LOCATION"U249"
$SEC"4"
CDS_SEC"4";
"PT31C||JTAGENB"
$PN"E14"14;
"PT44D||DONE"
$PN"E17"18;
"PT44C||INITN"
$PN"F16"17;
"PT31D||PROGRAMN"
$PN"E15"13;
"PT22D||TMS"
$PN"C10"15;
"PT22C||TCK"
$PN"D10"16;
"PT15D||TDI"
$PN"E9"76;
"PT15C||TDO"
$PN"E8"77;
%"Q_RES"
"1","(-975,-1150)","0","pure_quanta","I79";
;
PART_NUMBER"CS03322FB03"
TOLERANCE"1%"
VALUE"33.2"
MATERIAL"CHIP"
$LOCATION"R4751"
PACK_TYPE"0402LF"
WATTAGE"1/16W"
CDS_LIB"pure_quanta"
CDS_LOCATION"R4751"
$SEC"1"
CDS_SEC"1";
"B"
$PN"2"20;
"A"
$PN"1"4;
%"Q_RES"
"1","(-975,-1300)","0","pure_quanta","I86";
;
PART_NUMBER"CS03322FB03"
VALUE"33.2"
MATERIAL"CHIP"
TOLERANCE"1%"
$LOCATION"R4760"
PACK_TYPE"0402LF"
WATTAGE"1/16W"
CDS_LIB"pure_quanta"
CDS_LOCATION"R4760"
$SEC"1"
CDS_SEC"1";
"B"
$PN"2"19;
"A"
$PN"1"5;
%"Q_RES"
"1","(-975,-1475)","0","pure_quanta","I90";
;
PART_NUMBER"CS03322FB03"
TOLERANCE"1%"
VALUE"33.2"
MATERIAL"CHIP"
$LOCATION"R4765"
PACK_TYPE"0402LF"
WATTAGE"1/16W"
CDS_LIB"pure_quanta"
CDS_LOCATION"R4765"
$SEC"1"
CDS_SEC"1";
"B"
$PN"2"11;
"A"
$PN"1"6;
%"Q_RES"
"1","(-975,-1625)","0","pure_quanta","I95";
;
PART_NUMBER"CS03322FB03"
MATERIAL"CHIP"
TOLERANCE"1%"
VALUE"33.2"
$LOCATION"R4771"
CDS_LIB"pure_quanta"
PACK_TYPE"0402LF"
WATTAGE"1/16W"
CDS_LOCATION"R4771"
$SEC"1"
CDS_SEC"1";
"B"
$PN"2"3;
"A"
$PN"1"7;
END.
